(kicad_pcb
	(version 20260206)
	(generator "pcbnew")
	(generator_version "10.0")
	(general
		(thickness 1.6)
		(legacy_teardrops no)
	)
	(paper "A4")
	(title_block
		(title "01162023_DA0F0TEBIF0_F0T_Expander_BD_F_brd_V02_OCP.brd")
		(comment 1 "Grand Teton / footprints 4989-4996 of 9728")
	)
	(layers
		(0 "F.Cu" signal "TOP")
		(4 "In1.Cu" signal "GND")
		(6 "In2.Cu" signal "VCC")
		(8 "In3.Cu" signal "VCC1")
		(10 "In4.Cu" signal "GND1")
		(12 "In5.Cu" signal "IN1")
		(14 "In6.Cu" signal "GND2")
		(16 "In7.Cu" signal "IN2")
		(18 "In8.Cu" signal "GND3")
		(20 "In9.Cu" signal "IN3")
		(22 "In10.Cu" signal "GND4")
		(24 "In11.Cu" signal "IN4")
		(26 "In12.Cu" signal "GND5")
		(28 "In13.Cu" signal "IN5")
		(30 "In14.Cu" signal "GND6")
		(32 "In15.Cu" signal "IN6")
		(34 "In16.Cu" signal "GND7")
		(2 "B.Cu" signal "BOTTOM")
		(9 "F.Adhes" user "F.Adhesive")
		(11 "B.Adhes" user "B.Adhesive")
		(13 "F.Paste" user "Package Geometry/Pastemask Top")
		(15 "B.Paste" user "Package Geometry/Pastemask Bottom")
		(5 "F.SilkS" user "Ref Des/Silkscreen Top")
		(7 "B.SilkS" user "Ref Des/Silkscreen Bottom")
		(1 "F.Mask" user "Board Geometry/Soldermask Top")
		(3 "B.Mask" user "Board Geometry/Soldermask Bottom")
		(17 "Dwgs.User" user "User.Drawings")
		(19 "Cmts.User" user "User.Comments")
		(21 "Eco1.User" user "User.Eco1")
		(23 "Eco2.User" user "User.Eco2")
		(25 "Edge.Cuts" user "Board Geometry/Outline")
		(27 "Margin" user)
		(31 "F.CrtYd" user "Package Geometry/Place Bound Top")
		(29 "B.CrtYd" user "Package Geometry/Place Bound Bottom")
		(35 "F.Fab" user "Ref Des/Assembly Top")
		(33 "B.Fab" user "Ref Des/Assembly Bottom")
	)
	(footprint ""
		(layer "F.Cu")
		(at 286.385 -86.106 180)
		(property "Reference" "R489"
			(at 0 0 180)
			(layer "F.SilkS")
			(hide yes)
			(effects
				(font
					(size 1.27 1.27)
				)
			)
		)
		(property "Value" ""
			(at 0 0 180)
			(layer "F.Fab")
			(effects
				(font
					(size 1.27 1.27)
				)
			)
		)
		(duplicate_pad_numbers_are_jumpers no)
		(fp_line
			(start 0.7874 0.4064)
			(end -0.7874 0.4064)
			(stroke
				(width 0.1524)
				(type default)
			)
			(layer "F.SilkS")
		)
		(fp_line
			(start 0.7874 -0.4064)
			(end 0.7874 0.4064)
			(stroke
				(width 0.1524)
				(type default)
			)
			(layer "F.SilkS")
		)
		(fp_line
			(start -0.7874 0.4064)
			(end -0.7874 -0.4064)
			(stroke
				(width 0.1524)
				(type default)
			)
			(layer "F.SilkS")
		)
		(fp_line
			(start -0.7874 -0.4064)
			(end 0.7874 -0.4064)
			(stroke
				(width 0.1524)
				(type default)
			)
			(layer "F.SilkS")
		)
		(fp_line
			(start 0.67945 0.3048)
			(end 0.120396 0.3048)
			(stroke
				(width 0.1)
				(type default)
			)
			(layer "F.Fab")
		)
		(fp_line
			(start 0.67945 -0.3048)
			(end 0.67945 0.3048)
			(stroke
				(width 0.1)
				(type default)
			)
			(layer "F.Fab")
		)
		(fp_line
			(start 0.12065 -0.2794)
			(end 0.12065 -0.3048)
			(stroke
				(width 0.1)
				(type default)
			)
			(layer "F.Fab")
		)
		(fp_line
			(start 0.12065 -0.3048)
			(end 0.67945 -0.3048)
			(stroke
				(width 0.1)
				(type default)
			)
			(layer "F.Fab")
		)
		(fp_line
			(start 0.120396 0.3048)
			(end 0.120396 0.2794)
			(stroke
				(width 0.1)
				(type default)
			)
			(layer "F.Fab")
		)
		(fp_line
			(start 0.120396 0.2794)
			(end -0.12065 0.2794)
			(stroke
				(width 0.1)
				(type default)
			)
			(layer "F.Fab")
		)
		(fp_line
			(start -0.12065 0.3048)
			(end -0.67945 0.3048)
			(stroke
				(width 0.1)
				(type default)
			)
			(layer "F.Fab")
		)
		(fp_line
			(start -0.12065 0.2794)
			(end -0.12065 0.3048)
			(stroke
				(width 0.1)
				(type default)
			)
			(layer "F.Fab")
		)
		(fp_line
			(start -0.12065 -0.2794)
			(end 0.12065 -0.2794)
			(stroke
				(width 0.1)
				(type default)
			)
			(layer "F.Fab")
		)
		(fp_line
			(start -0.12065 -0.305054)
			(end -0.12065 -0.2794)
			(stroke
				(width 0.1)
				(type default)
			)
			(layer "F.Fab")
		)
		(fp_line
			(start -0.67945 0.3048)
			(end -0.67945 -0.305054)
			(stroke
				(width 0.1)
				(type default)
			)
			(layer "F.Fab")
		)
		(fp_line
			(start -0.67945 -0.305054)
			(end -0.12065 -0.305054)
			(stroke
				(width 0.1)
				(type default)
			)
			(layer "F.Fab")
		)
		(pad "1" smd circle
			(at -0.40005 0 180)
			(size 0 0)
			(layers "F.Cu" "F.Mask" "F.Paste")
			(net "BB_FRU_A0")
		)
		(pad "2" smd circle
			(at 0.40005 0 180)
			(size 0 0)
			(layers "F.Cu" "F.Mask" "F.Paste")
			(net "GND")
		)
	)
	(footprint ""
		(layer "F.Cu")
		(at 368.959638 -61.612526)
		(property "Reference" "PD41"
			(at -3.7084 -2.733548 0)
			(unlocked yes)
			(layer "F.SilkS")
			(effects
				(font
					(size 0.7874 0.5842)
					(thickness 0.1524)
				)
				(justify left)
			)
		)
		(property "Value" ""
			(at 0 0 0)
			(layer "F.Fab")
			(effects
				(font
					(size 1.27 1.27)
				)
			)
		)
		(duplicate_pad_numbers_are_jumpers no)
		(fp_line
			(start -3.656584 -1.970024)
			(end -3.656584 1.970024)
			(stroke
				(width 0.1524)
				(type default)
			)
			(layer "F.SilkS")
		)
		(fp_line
			(start -3.656584 1.970024)
			(end 4.240784 1.970024)
			(stroke
				(width 0.1524)
				(type default)
			)
			(layer "F.SilkS")
		)
		(fp_line
			(start 4.240784 -1.970024)
			(end -3.656584 -1.970024)
			(stroke
				(width 0.1524)
				(type default)
			)
			(layer "F.SilkS")
		)
		(fp_line
			(start 4.240784 1.970024)
			(end 4.240784 -1.970024)
			(stroke
				(width 0.1524)
				(type default)
			)
			(layer "F.SilkS")
		)
		(fp_poly
			(pts
				(xy 3.580384 1.970024) (xy 3.580384 -1.970024) (xy 4.240784 -1.970024) (xy 4.240784 1.970024)
			)
			(stroke
				(width 0)
				(type default)
			)
			(fill yes)
			(layer "F.SilkS")
		)
		(fp_line
			(start -2.3749 -1.970024)
			(end -2.3749 1.970024)
			(stroke
				(width 0.1)
				(type default)
			)
			(layer "F.Fab")
		)
		(fp_line
			(start -2.3749 1.970024)
			(end 2.3749 1.970024)
			(stroke
				(width 0.1)
				(type default)
			)
			(layer "F.Fab")
		)
		(fp_line
			(start 2.3749 -1.970024)
			(end -2.3749 -1.970024)
			(stroke
				(width 0.1)
				(type default)
			)
			(layer "F.Fab")
		)
		(fp_line
			(start 2.3749 1.970024)
			(end 2.3749 -1.970024)
			(stroke
				(width 0.1)
				(type default)
			)
			(layer "F.Fab")
		)
		(fp_text user "+"
			(at -4.9784 -0.23495 0)
			(unlocked yes)
			(layer "F.Fab")
			(effects
				(font
					(size 1.905 1.4224)
					(thickness 0.1524)
				)
				(justify left)
			)
		)
		(fp_text user "-"
			(at 4.1656 -0.23495 0)
			(unlocked yes)
			(layer "F.Fab")
			(effects
				(font
					(size 1.905 1.4224)
					(thickness 0.1524)
				)
				(justify left)
			)
		)
		(pad "A" smd rect
			(at -2.450084 0)
			(size 2.159 2.2606)
			(layers "F.Cu" "F.Mask" "F.Paste")
			(net "GND")
		)
		(pad "C" smd rect
			(at 2.450084 0)
			(size 2.159 2.2606)
			(layers "F.Cu" "F.Mask" "F.Paste")
			(net "P12V_AUX")
		)
	)
	(footprint ""
		(layer "F.Cu")
		(at 171.487592 -356.244906 90)
		(property "Reference" "C2522"
			(at 0 0 90)
			(layer "F.SilkS")
			(hide yes)
			(effects
				(font
					(size 1.27 1.27)
				)
			)
		)
		(property "Value" ""
			(at 0 0 90)
			(layer "F.Fab")
			(effects
				(font
					(size 1.27 1.27)
				)
			)
		)
		(duplicate_pad_numbers_are_jumpers no)
		(fp_line
			(start 0.299974 -0.150114)
			(end 0.299974 0.150114)
			(stroke
				(width 0.1)
				(type default)
			)
			(layer "F.Fab")
		)
		(fp_line
			(start -0.299974 -0.150114)
			(end 0.299974 -0.150114)
			(stroke
				(width 0.1)
				(type default)
			)
			(layer "F.Fab")
		)
		(fp_line
			(start 0.299974 0.150114)
			(end -0.299974 0.150114)
			(stroke
				(width 0.1)
				(type default)
			)
			(layer "F.Fab")
		)
		(fp_line
			(start -0.299974 0.150114)
			(end -0.299974 -0.150114)
			(stroke
				(width 0.1)
				(type default)
			)
			(layer "F.Fab")
		)
		(pad "1" smd rect
			(at -0.2667 0 90)
			(size 0.3048 0.381)
			(layers "F.Cu" "F.Mask" "F.Paste")
			(net "P5E_PEX1_STN4_TX_DP<74>")
		)
		(pad "2" smd rect
			(at 0.2667 0 90)
			(size 0.3048 0.381)
			(layers "F.Cu" "F.Mask" "F.Paste")
			(net "P5E_PEX1_STN4_TX_C_DP<74>")
		)
	)
	(footprint ""
		(layer "F.Cu")
		(at 122.219212 -59.574684 90)
		(property "Reference" "PC540"
			(at 0 0 90)
			(layer "F.SilkS")
			(hide yes)
			(effects
				(font
					(size 1.27 1.27)
				)
			)
		)
		(property "Value" ""
			(at 0 0 90)
			(layer "F.Fab")
			(effects
				(font
					(size 1.27 1.27)
				)
			)
		)
		(duplicate_pad_numbers_are_jumpers no)
		(fp_line
			(start 0.7874 -0.4064)
			(end 0.7874 0.4064)
			(stroke
				(width 0.1524)
				(type default)
			)
			(layer "F.SilkS")
		)
		(fp_line
			(start -0.7874 -0.4064)
			(end 0.7874 -0.4064)
			(stroke
				(width 0.1524)
				(type default)
			)
			(layer "F.SilkS")
		)
		(fp_line
			(start 0.7874 0.4064)
			(end -0.7874 0.4064)
			(stroke
				(width 0.1524)
				(type default)
			)
			(layer "F.SilkS")
		)
		(fp_line
			(start -0.7874 0.4064)
			(end -0.7874 -0.4064)
			(stroke
				(width 0.1524)
				(type default)
			)
			(layer "F.SilkS")
		)
		(fp_line
			(start -0.12065 -0.305054)
			(end -0.12065 -0.2794)
			(stroke
				(width 0.1)
				(type default)
			)
			(layer "F.Fab")
		)
		(fp_line
			(start -0.67945 -0.305054)
			(end -0.12065 -0.305054)
			(stroke
				(width 0.1)
				(type default)
			)
			(layer "F.Fab")
		)
		(fp_line
			(start 0.67945 -0.3048)
			(end 0.67945 0.3048)
			(stroke
				(width 0.1)
				(type default)
			)
			(layer "F.Fab")
		)
		(fp_line
			(start 0.12065 -0.3048)
			(end 0.67945 -0.3048)
			(stroke
				(width 0.1)
				(type default)
			)
			(layer "F.Fab")
		)
		(fp_line
			(start 0.12065 -0.2794)
			(end 0.12065 -0.3048)
			(stroke
				(width 0.1)
				(type default)
			)
			(layer "F.Fab")
		)
		(fp_line
			(start -0.12065 -0.2794)
			(end 0.12065 -0.2794)
			(stroke
				(width 0.1)
				(type default)
			)
			(layer "F.Fab")
		)
		(fp_line
			(start 0.120396 0.2794)
			(end -0.12065 0.2794)
			(stroke
				(width 0.1)
				(type default)
			)
			(layer "F.Fab")
		)
		(fp_line
			(start -0.12065 0.2794)
			(end -0.12065 0.3048)
			(stroke
				(width 0.1)
				(type default)
			)
			(layer "F.Fab")
		)
		(fp_line
			(start 0.67945 0.3048)
			(end 0.120396 0.3048)
			(stroke
				(width 0.1)
				(type default)
			)
			(layer "F.Fab")
		)
		(fp_line
			(start 0.120396 0.3048)
			(end 0.120396 0.2794)
			(stroke
				(width 0.1)
				(type default)
			)
			(layer "F.Fab")
		)
		(fp_line
			(start -0.12065 0.3048)
			(end -0.67945 0.3048)
			(stroke
				(width 0.1)
				(type default)
			)
			(layer "F.Fab")
		)
		(fp_line
			(start -0.67945 0.3048)
			(end -0.67945 -0.305054)
			(stroke
				(width 0.1)
				(type default)
			)
			(layer "F.Fab")
		)
		(pad "1" smd circle
			(at -0.40005 0 90)
			(size 0 0)
			(layers "F.Cu" "F.Mask" "F.Paste")
			(net "P5V_AUX")
		)
		(pad "2" smd circle
			(at 0.40005 0 90)
			(size 0 0)
			(layers "F.Cu" "F.Mask" "F.Paste")
			(net "GND")
		)
	)
	(footprint ""
		(layer "F.Cu")
		(at 349.899986 -72.69988)
		(property "Reference" "H60"
			(at -4.574794 -5.022342 0)
			(unlocked yes)
			(layer "F.SilkS")
			(effects
				(font
					(size 0.7874 0.5842)
					(thickness 0.1524)
				)
				(justify left)
			)
		)
		(property "Value" ""
			(at 0 0 0)
			(layer "F.Fab")
			(effects
				(font
					(size 1.27 1.27)
				)
			)
		)
		(duplicate_pad_numbers_are_jumpers no)
		(pad "1" thru_hole circle
			(at 0 0)
			(size 10.0076 10.0076)
			(drill 5.6134)
			(layers "*.Cu" "*.Mask")
			(remove_unused_layers no)
			(net "GND")
			(clearance -1.9431)
		)
	)
	(footprint ""
		(layer "F.Cu")
		(at 321.201542 -304.036476 90)
		(property "Reference" "R1383"
			(at 0 0 90)
			(layer "F.SilkS")
			(hide yes)
			(effects
				(font
					(size 1.27 1.27)
				)
			)
		)
		(property "Value" ""
			(at 0 0 90)
			(layer "F.Fab")
			(effects
				(font
					(size 1.27 1.27)
				)
			)
		)
		(duplicate_pad_numbers_are_jumpers no)
		(fp_line
			(start 0.7874 -0.4064)
			(end 0.7874 0.4064)
			(stroke
				(width 0.1524)
				(type default)
			)
			(layer "F.SilkS")
		)
		(fp_line
			(start -0.7874 -0.4064)
			(end 0.7874 -0.4064)
			(stroke
				(width 0.1524)
				(type default)
			)
			(layer "F.SilkS")
		)
		(fp_line
			(start 0.7874 0.4064)
			(end -0.7874 0.4064)
			(stroke
				(width 0.1524)
				(type default)
			)
			(layer "F.SilkS")
		)
		(fp_line
			(start -0.7874 0.4064)
			(end -0.7874 -0.4064)
			(stroke
				(width 0.1524)
				(type default)
			)
			(layer "F.SilkS")
		)
		(fp_line
			(start -0.12065 -0.305054)
			(end -0.12065 -0.2794)
			(stroke
				(width 0.1)
				(type default)
			)
			(layer "F.Fab")
		)
		(fp_line
			(start -0.67945 -0.305054)
			(end -0.12065 -0.305054)
			(stroke
				(width 0.1)
				(type default)
			)
			(layer "F.Fab")
		)
		(fp_line
			(start 0.67945 -0.3048)
			(end 0.67945 0.3048)
			(stroke
				(width 0.1)
				(type default)
			)
			(layer "F.Fab")
		)
		(fp_line
			(start 0.12065 -0.3048)
			(end 0.67945 -0.3048)
			(stroke
				(width 0.1)
				(type default)
			)
			(layer "F.Fab")
		)
		(fp_line
			(start 0.12065 -0.2794)
			(end 0.12065 -0.3048)
			(stroke
				(width 0.1)
				(type default)
			)
			(layer "F.Fab")
		)
		(fp_line
			(start -0.12065 -0.2794)
			(end 0.12065 -0.2794)
			(stroke
				(width 0.1)
				(type default)
			)
			(layer "F.Fab")
		)
		(fp_line
			(start 0.120396 0.2794)
			(end -0.12065 0.2794)
			(stroke
				(width 0.1)
				(type default)
			)
			(layer "F.Fab")
		)
		(fp_line
			(start -0.12065 0.2794)
			(end -0.12065 0.3048)
			(stroke
				(width 0.1)
				(type default)
			)
			(layer "F.Fab")
		)
		(fp_line
			(start 0.67945 0.3048)
			(end 0.120396 0.3048)
			(stroke
				(width 0.1)
				(type default)
			)
			(layer "F.Fab")
		)
		(fp_line
			(start 0.120396 0.3048)
			(end 0.120396 0.2794)
			(stroke
				(width 0.1)
				(type default)
			)
			(layer "F.Fab")
		)
		(fp_line
			(start -0.12065 0.3048)
			(end -0.67945 0.3048)
			(stroke
				(width 0.1)
				(type default)
			)
			(layer "F.Fab")
		)
		(fp_line
			(start -0.67945 0.3048)
			(end -0.67945 -0.305054)
			(stroke
				(width 0.1)
				(type default)
			)
			(layer "F.Fab")
		)
		(pad "1" smd circle
			(at -0.40005 0 90)
			(size 0 0)
			(layers "F.Cu" "F.Mask" "F.Paste")
			(net "GND")
		)
		(pad "2" smd circle
			(at 0.40005 0 90)
			(size 0 0)
			(layers "F.Cu" "F.Mask" "F.Paste")
			(net "PEX2_SPARE4")
		)
	)
	(footprint ""
		(layer "F.Cu")
		(at 323.91477 -216.415366 180)
		(property "Reference" "R2985"
			(at 0 0 180)
			(layer "F.SilkS")
			(hide yes)
			(effects
				(font
					(size 1.27 1.27)
				)
			)
		)
		(property "Value" ""
			(at 0 0 180)
			(layer "F.Fab")
			(effects
				(font
					(size 1.27 1.27)
				)
			)
		)
		(duplicate_pad_numbers_are_jumpers no)
		(fp_line
			(start 0.7874 0.4064)
			(end -0.7874 0.4064)
			(stroke
				(width 0.1524)
				(type default)
			)
			(layer "F.SilkS")
		)
		(fp_line
			(start 0.7874 -0.4064)
			(end 0.7874 0.4064)
			(stroke
				(width 0.1524)
				(type default)
			)
			(layer "F.SilkS")
		)
		(fp_line
			(start -0.7874 0.4064)
			(end -0.7874 -0.4064)
			(stroke
				(width 0.1524)
				(type default)
			)
			(layer "F.SilkS")
		)
		(fp_line
			(start -0.7874 -0.4064)
			(end 0.7874 -0.4064)
			(stroke
				(width 0.1524)
				(type default)
			)
			(layer "F.SilkS")
		)
		(fp_line
			(start 0.67945 0.3048)
			(end 0.120396 0.3048)
			(stroke
				(width 0.1)
				(type default)
			)
			(layer "F.Fab")
		)
		(fp_line
			(start 0.67945 -0.3048)
			(end 0.67945 0.3048)
			(stroke
				(width 0.1)
				(type default)
			)
			(layer "F.Fab")
		)
		(fp_line
			(start 0.12065 -0.2794)
			(end 0.12065 -0.3048)
			(stroke
				(width 0.1)
				(type default)
			)
			(layer "F.Fab")
		)
		(fp_line
			(start 0.12065 -0.3048)
			(end 0.67945 -0.3048)
			(stroke
				(width 0.1)
				(type default)
			)
			(layer "F.Fab")
		)
		(fp_line
			(start 0.120396 0.3048)
			(end 0.120396 0.2794)
			(stroke
				(width 0.1)
				(type default)
			)
			(layer "F.Fab")
		)
		(fp_line
			(start 0.120396 0.2794)
			(end -0.12065 0.2794)
			(stroke
				(width 0.1)
				(type default)
			)
			(layer "F.Fab")
		)
		(fp_line
			(start -0.12065 0.3048)
			(end -0.67945 0.3048)
			(stroke
				(width 0.1)
				(type default)
			)
			(layer "F.Fab")
		)
		(fp_line
			(start -0.12065 0.2794)
			(end -0.12065 0.3048)
			(stroke
				(width 0.1)
				(type default)
			)
			(layer "F.Fab")
		)
		(fp_line
			(start -0.12065 -0.2794)
			(end 0.12065 -0.2794)
			(stroke
				(width 0.1)
				(type default)
			)
			(layer "F.Fab")
		)
		(fp_line
			(start -0.12065 -0.305054)
			(end -0.12065 -0.2794)
			(stroke
				(width 0.1)
				(type default)
			)
			(layer "F.Fab")
		)
		(fp_line
			(start -0.67945 0.3048)
			(end -0.67945 -0.305054)
			(stroke
				(width 0.1)
				(type default)
			)
			(layer "F.Fab")
		)
		(fp_line
			(start -0.67945 -0.305054)
			(end -0.12065 -0.305054)
			(stroke
				(width 0.1)
				(type default)
			)
			(layer "F.Fab")
		)
		(pad "1" smd circle
			(at -0.40005 0 180)
			(size 0 0)
			(layers "F.Cu" "F.Mask" "F.Paste")
			(net "LED_POSTCODE_7")
		)
		(pad "2" smd circle
			(at 0.40005 0 180)
			(size 0 0)
			(layers "F.Cu" "F.Mask" "F.Paste")
			(net "LED_POSTCODE_R_7")
		)
	)
	(footprint ""
		(layer "F.Cu")
		(at 214.194136 -181.613556 -90)
		(property "Reference" "R5298"
			(at 0 0 270)
			(layer "F.SilkS")
			(hide yes)
			(effects
				(font
					(size 1.27 1.27)
				)
			)
		)
		(property "Value" ""
			(at 0 0 270)
			(layer "F.Fab")
			(effects
				(font
					(size 1.27 1.27)
				)
			)
		)
		(duplicate_pad_numbers_are_jumpers no)
		(fp_line
			(start -0.7874 0.4064)
			(end -0.7874 -0.4064)
			(stroke
				(width 0.1524)
				(type default)
			)
			(layer "F.SilkS")
		)
		(fp_line
			(start 0.7874 0.4064)
			(end -0.7874 0.4064)
			(stroke
				(width 0.1524)
				(type default)
			)
			(layer "F.SilkS")
		)
		(fp_line
			(start -0.7874 -0.4064)
			(end 0.7874 -0.4064)
			(stroke
				(width 0.1524)
				(type default)
			)
			(layer "F.SilkS")
		)
		(fp_line
			(start 0.7874 -0.4064)
			(end 0.7874 0.4064)
			(stroke
				(width 0.1524)
				(type default)
			)
			(layer "F.SilkS")
		)
		(fp_line
			(start -0.67945 0.3048)
			(end -0.67945 -0.305054)
			(stroke
				(width 0.1)
				(type default)
			)
			(layer "F.Fab")
		)
		(fp_line
			(start -0.12065 0.3048)
			(end -0.67945 0.3048)
			(stroke
				(width 0.1)
				(type default)
			)
			(layer "F.Fab")
		)
		(fp_line
			(start 0.120396 0.3048)
			(end 0.120396 0.2794)
			(stroke
				(width 0.1)
				(type default)
			)
			(layer "F.Fab")
		)
		(fp_line
			(start 0.67945 0.3048)
			(end 0.120396 0.3048)
			(stroke
				(width 0.1)
				(type default)
			)
			(layer "F.Fab")
		)
		(fp_line
			(start -0.12065 0.2794)
			(end -0.12065 0.3048)
			(stroke
				(width 0.1)
				(type default)
			)
			(layer "F.Fab")
		)
		(fp_line
			(start 0.120396 0.2794)
			(end -0.12065 0.2794)
			(stroke
				(width 0.1)
				(type default)
			)
			(layer "F.Fab")
		)
		(fp_line
			(start -0.12065 -0.2794)
			(end 0.12065 -0.2794)
			(stroke
				(width 0.1)
				(type default)
			)
			(layer "F.Fab")
		)
		(fp_line
			(start 0.12065 -0.2794)
			(end 0.12065 -0.3048)
			(stroke
				(width 0.1)
				(type default)
			)
			(layer "F.Fab")
		)
		(fp_line
			(start 0.12065 -0.3048)
			(end 0.67945 -0.3048)
			(stroke
				(width 0.1)
				(type default)
			)
			(layer "F.Fab")
		)
		(fp_line
			(start 0.67945 -0.3048)
			(end 0.67945 0.3048)
			(stroke
				(width 0.1)
				(type default)
			)
			(layer "F.Fab")
		)
		(fp_line
			(start -0.67945 -0.305054)
			(end -0.12065 -0.305054)
			(stroke
				(width 0.1)
				(type default)
			)
			(layer "F.Fab")
		)
		(fp_line
			(start -0.12065 -0.305054)
			(end -0.12065 -0.2794)
			(stroke
				(width 0.1)
				(type default)
			)
			(layer "F.Fab")
		)
		(pad "1" smd circle
			(at -0.40005 0 270)
			(size 0 0)
			(layers "F.Cu" "F.Mask" "F.Paste")
			(net "SEL_FLASH_PEX1_BUF")
		)
		(pad "2" smd circle
			(at 0.40005 0 270)
			(size 0 0)
			(layers "F.Cu" "F.Mask" "F.Paste")
			(net "SEL_FLASH_PEX1_BUF_R")
		)
	)
)
